# T6G (Grand Teton) — schematic netlist excerpt (pin names and nets, part order shuffled) for the footprints in the layout excerpt that follows; sources: Cadence DE-HDL packaged netlist, KiCad conversion of 04192023_DAF0TMB3IC0_F0TG_MB_C_brd_V02_OCP.brd

PC6544  Q_CAP  1UF 16V 10% X6S  pkg C0402  page 364 : A = P0V9_RETIMER_CPU1_VCC ; B = GND
C2475  Q_CAP  22UF 4V 20% X6S  pkg C0402  page 74 : A = PVDDCR_SOC_P1 ; B = GND

(kicad_pcb
	(version 20260206)
	(generator "pcbnew")
	(generator_version "10.0")
	(general
		(thickness 1.6)
		(legacy_teardrops no)
	)
	(paper "A4")
	(title_block
		(title "04192023_DAF0TMB3IC0_F0TG_MB_C_brd_V02_OCP.brd")
		(comment 1 "Grand Teton / footprints 495-497 of 8354")
	)
	(layers
		(0 "F.Cu" signal "TOP")
		(4 "In1.Cu" signal "GND")
		(6 "In2.Cu" signal "IN1")
		(8 "In3.Cu" signal "GND1")
		(10 "In4.Cu" signal "IN2")
		(12 "In5.Cu" signal "GND2")
		(14 "In6.Cu" signal "IN3")
		(16 "In7.Cu" signal "GND3")
		(18 "In8.Cu" signal "VCC")
		(20 "In9.Cu" signal "VCC1")
		(22 "In10.Cu" signal "GND4")
		(24 "In11.Cu" signal "IN4")
		(26 "In12.Cu" signal "GND5")
		(28 "In13.Cu" signal "IN5")
		(30 "In14.Cu" signal "GND6")
		(32 "In15.Cu" signal "IN6")
		(34 "In16.Cu" signal "GND7")
		(2 "B.Cu" signal "BOTTOM")
		(9 "F.Adhes" user "F.Adhesive")
		(11 "B.Adhes" user "B.Adhesive")
		(13 "F.Paste" user "Package Geometry/Pastemask Top")
		(15 "B.Paste" user "Package Geometry/Pastemask Bottom")
		(5 "F.SilkS" user "Ref Des/Silkscreen Top")
		(7 "B.SilkS" user "Ref Des/Silkscreen Bottom")
		(1 "F.Mask" user "Board Geometry/Soldermask Top")
		(3 "B.Mask" user "Board Geometry/Soldermask Bottom")
		(17 "Dwgs.User" user "User.Drawings")
		(19 "Cmts.User" user "User.Comments")
		(21 "Eco1.User" user "User.Eco1")
		(23 "Eco2.User" user "User.Eco2")
		(25 "Edge.Cuts" user "Board Geometry/Outline")
		(27 "Margin" user)
		(31 "F.CrtYd" user "Package Geometry/Place Bound Top")
		(29 "B.CrtYd" user "Package Geometry/Place Bound Bottom")
		(35 "F.Fab" user "Ref Des/Assembly Top")
		(33 "B.Fab" user "Ref Des/Assembly Bottom")
	)
	(footprint ""
		(layer "F.Cu")
		(at 10.066782 -406.119584 180)
		(property "Reference" "PC6544"
			(at 0 0 180)
			(layer "F.SilkS")
			(hide yes)
			(effects
				(font
					(size 1.27 1.27)
				)
			)
		)
		(property "Value" ""
			(at 0 0 180)
			(layer "F.Fab")
			(effects
				(font
					(size 1.27 1.27)
				)
			)
		)
		(duplicate_pad_numbers_are_jumpers no)
		(fp_line
			(start 0.7874 0.4064)
			(end -0.7874 0.4064)
			(stroke
				(width 0.1524)
				(type default)
			)
			(layer "F.SilkS")
		)
		(fp_line
			(start 0.7874 -0.4064)
			(end 0.7874 0.4064)
			(stroke
				(width 0.1524)
				(type default)
			)
			(layer "F.SilkS")
		)
		(fp_line
			(start -0.7874 0.4064)
			(end -0.7874 -0.4064)
			(stroke
				(width 0.1524)
				(type default)
			)
			(layer "F.SilkS")
		)
		(fp_line
			(start -0.7874 -0.4064)
			(end 0.7874 -0.4064)
			(stroke
				(width 0.1524)
				(type default)
			)
			(layer "F.SilkS")
		)
		(fp_line
			(start 0.67945 0.3048)
			(end 0.120396 0.3048)
			(stroke
				(width 0.1)
				(type default)
			)
			(layer "F.Fab")
		)
		(fp_line
			(start 0.67945 -0.3048)
			(end 0.67945 0.3048)
			(stroke
				(width 0.1)
				(type default)
			)
			(layer "F.Fab")
		)
		(fp_line
			(start 0.12065 -0.2794)
			(end 0.12065 -0.3048)
			(stroke
				(width 0.1)
				(type default)
			)
			(layer "F.Fab")
		)
		(fp_line
			(start 0.12065 -0.3048)
			(end 0.67945 -0.3048)
			(stroke
				(width 0.1)
				(type default)
			)
			(layer "F.Fab")
		)
		(fp_line
			(start 0.120396 0.3048)
			(end 0.120396 0.2794)
			(stroke
				(width 0.1)
				(type default)
			)
			(layer "F.Fab")
		)
		(fp_line
			(start 0.120396 0.2794)
			(end -0.12065 0.2794)
			(stroke
				(width 0.1)
				(type default)
			)
			(layer "F.Fab")
		)
		(fp_line
			(start -0.12065 0.3048)
			(end -0.67945 0.3048)
			(stroke
				(width 0.1)
				(type default)
			)
			(layer "F.Fab")
		)
		(fp_line
			(start -0.12065 0.2794)
			(end -0.12065 0.3048)
			(stroke
				(width 0.1)
				(type default)
			)
			(layer "F.Fab")
		)
		(fp_line
			(start -0.12065 -0.2794)
			(end 0.12065 -0.2794)
			(stroke
				(width 0.1)
				(type default)
			)
			(layer "F.Fab")
		)
		(fp_line
			(start -0.12065 -0.305054)
			(end -0.12065 -0.2794)
			(stroke
				(width 0.1)
				(type default)
			)
			(layer "F.Fab")
		)
		(fp_line
			(start -0.67945 0.3048)
			(end -0.67945 -0.305054)
			(stroke
				(width 0.1)
				(type default)
			)
			(layer "F.Fab")
		)
		(fp_line
			(start -0.67945 -0.305054)
			(end -0.12065 -0.305054)
			(stroke
				(width 0.1)
				(type default)
			)
			(layer "F.Fab")
		)
		(pad "1" smd circle
			(at -0.40005 0 180)
			(size 0 0)
			(layers "F.Cu" "F.Mask" "F.Paste")
			(net "P0V9_RETIMER_CPU1_VCC")
		)
		(pad "2" smd circle
			(at 0.40005 0 180)
			(size 0 0)
			(layers "F.Cu" "F.Mask" "F.Paste")
			(net "GND")
		)
	)
	(footprint ""
		(layer "F.Cu")
		(at 59.169808 -71.527416)
		(property "Reference" "ME3"
			(at 0 0 0)
			(layer "F.SilkS")
			(hide yes)
			(effects
				(font
					(size 1.27 1.27)
				)
			)
		)
		(property "Value" ""
			(at 0 0 0)
			(layer "F.Fab")
			(effects
				(font
					(size 1.27 1.27)
				)
			)
		)
		(duplicate_pad_numbers_are_jumpers no)
	)
	(footprint ""
		(layer "F.Cu")
		(at 110.525814 -256.012442 90)
		(property "Reference" "C2475"
			(at 0 0 90)
			(layer "F.SilkS")
			(hide yes)
			(effects
				(font
					(size 1.27 1.27)
				)
			)
		)
		(property "Value" ""
			(at 0 0 90)
			(layer "F.Fab")
			(effects
				(font
					(size 1.27 1.27)
				)
			)
		)
		(duplicate_pad_numbers_are_jumpers no)
		(fp_line
			(start 0.7874 -0.4064)
			(end 0.7874 0.4064)
			(stroke
				(width 0.1524)
				(type default)
			)
			(layer "F.SilkS")
		)
		(fp_line
			(start -0.7874 -0.4064)
			(end 0.7874 -0.4064)
			(stroke
				(width 0.1524)
				(type default)
			)
			(layer "F.SilkS")
		)
		(fp_line
			(start 0.7874 0.4064)
			(end -0.7874 0.4064)
			(stroke
				(width 0.1524)
				(type default)
			)
			(layer "F.SilkS")
		)
		(fp_line
			(start -0.7874 0.4064)
			(end -0.7874 -0.4064)
			(stroke
				(width 0.1524)
				(type default)
			)
			(layer "F.SilkS")
		)
		(fp_line
			(start -0.12065 -0.305054)
			(end -0.12065 -0.2794)
			(stroke
				(width 0.1)
				(type default)
			)
			(layer "F.Fab")
		)
		(fp_line
			(start -0.67945 -0.305054)
			(end -0.12065 -0.305054)
			(stroke
				(width 0.1)
				(type default)
			)
			(layer "F.Fab")
		)
		(fp_line
			(start 0.67945 -0.3048)
			(end 0.67945 0.3048)
			(stroke
				(width 0.1)
				(type default)
			)
			(layer "F.Fab")
		)
		(fp_line
			(start 0.12065 -0.3048)
			(end 0.67945 -0.3048)
			(stroke
				(width 0.1)
				(type default)
			)
			(layer "F.Fab")
		)
		(fp_line
			(start 0.12065 -0.2794)
			(end 0.12065 -0.3048)
			(stroke
				(width 0.1)
				(type default)
			)
			(layer "F.Fab")
		)
		(fp_line
			(start -0.12065 -0.2794)
			(end 0.12065 -0.2794)
			(stroke
				(width 0.1)
				(type default)
			)
			(layer "F.Fab")
		)
		(fp_line
			(start 0.120396 0.2794)
			(end -0.12065 0.2794)
			(stroke
				(width 0.1)
				(type default)
			)
			(layer "F.Fab")
		)
		(fp_line
			(start -0.12065 0.2794)
			(end -0.12065 0.3048)
			(stroke
				(width 0.1)
				(type default)
			)
			(layer "F.Fab")
		)
		(fp_line
			(start 0.67945 0.3048)
			(end 0.120396 0.3048)
			(stroke
				(width 0.1)
				(type default)
			)
			(layer "F.Fab")
		)
		(fp_line
			(start 0.120396 0.3048)
			(end 0.120396 0.2794)
			(stroke
				(width 0.1)
				(type default)
			)
			(layer "F.Fab")
		)
		(fp_line
			(start -0.12065 0.3048)
			(end -0.67945 0.3048)
			(stroke
				(width 0.1)
				(type default)
			)
			(layer "F.Fab")
		)
		(fp_line
			(start -0.67945 0.3048)
			(end -0.67945 -0.305054)
			(stroke
				(width 0.1)
				(type default)
			)
			(layer "F.Fab")
		)
		(pad "1" smd circle
			(at -0.40005 0 90)
			(size 0 0)
			(layers "F.Cu" "F.Mask" "F.Paste")
			(net "PVDDCR_SOC_P1")
		)
		(pad "2" smd circle
			(at 0.40005 0 90)
			(size 0 0)
			(layers "F.Cu" "F.Mask" "F.Paste")
			(net "GND")
		)
	)
)
